(kicad_pcb
	(version 20260206)
	(generator "pcbnew")
	(generator_version "10.0")
	(general
		(thickness 1.6)
		(legacy_teardrops no)
	)
	(paper "A4")
	(title_block
		(title "12092022_DA0F0TFB6D0_F0T_FAN_BOARD_MP5048_D_brd_v02_OCP.brd")
		(comment 1 "Grand Teton / footprints 62-67 of 924")
	)
	(layers
		(0 "F.Cu" signal "TOP")
		(4 "In1.Cu" signal "GND")
		(6 "In2.Cu" signal "IN1")
		(8 "In3.Cu" signal "IN2")
		(10 "In4.Cu" signal "GND1")
		(2 "B.Cu" signal "BOTTOM")
		(9 "F.Adhes" user "F.Adhesive")
		(11 "B.Adhes" user "B.Adhesive")
		(13 "F.Paste" user "Package Geometry/Pastemask Top")
		(15 "B.Paste" user "Package Geometry/Pastemask Bottom")
		(5 "F.SilkS" user "Ref Des/Silkscreen Top")
		(7 "B.SilkS" user "Ref Des/Silkscreen Bottom")
		(1 "F.Mask" user "Board Geometry/Soldermask Top")
		(3 "B.Mask" user "Board Geometry/Soldermask Bottom")
		(17 "Dwgs.User" user "User.Drawings")
		(19 "Cmts.User" user "User.Comments")
		(21 "Eco1.User" user "User.Eco1")
		(23 "Eco2.User" user "User.Eco2")
		(25 "Edge.Cuts" user "Board Geometry/Outline")
		(27 "Margin" user)
		(31 "F.CrtYd" user "Package Geometry/Place Bound Top")
		(29 "B.CrtYd" user "Package Geometry/Place Bound Bottom")
		(35 "F.Fab" user "Ref Des/Assembly Top")
		(33 "B.Fab" user "Ref Des/Assembly Bottom")
	)
	(footprint ""
		(layer "F.Cu")
		(at 32.893 -28.956 180)
		(property "Reference" "R5326"
			(at 0 0 180)
			(layer "F.SilkS")
			(hide yes)
			(effects
				(font
					(size 1.27 1.27)
				)
			)
		)
		(property "Value" ""
			(at 0 0 180)
			(layer "F.Fab")
			(effects
				(font
					(size 1.27 1.27)
				)
			)
		)
		(duplicate_pad_numbers_are_jumpers no)
		(fp_line
			(start 0.7874 0.4064)
			(end -0.7874 0.4064)
			(stroke
				(width 0.1524)
				(type default)
			)
			(layer "F.SilkS")
		)
		(fp_line
			(start 0.7874 -0.4064)
			(end 0.7874 0.4064)
			(stroke
				(width 0.1524)
				(type default)
			)
			(layer "F.SilkS")
		)
		(fp_line
			(start -0.7874 0.4064)
			(end -0.7874 -0.4064)
			(stroke
				(width 0.1524)
				(type default)
			)
			(layer "F.SilkS")
		)
		(fp_line
			(start -0.7874 -0.4064)
			(end 0.7874 -0.4064)
			(stroke
				(width 0.1524)
				(type default)
			)
			(layer "F.SilkS")
		)
		(fp_line
			(start 0.67945 0.3048)
			(end 0.120396 0.3048)
			(stroke
				(width 0.1)
				(type default)
			)
			(layer "F.Fab")
		)
		(fp_line
			(start 0.67945 -0.3048)
			(end 0.67945 0.3048)
			(stroke
				(width 0.1)
				(type default)
			)
			(layer "F.Fab")
		)
		(fp_line
			(start 0.12065 -0.2794)
			(end 0.12065 -0.3048)
			(stroke
				(width 0.1)
				(type default)
			)
			(layer "F.Fab")
		)
		(fp_line
			(start 0.12065 -0.3048)
			(end 0.67945 -0.3048)
			(stroke
				(width 0.1)
				(type default)
			)
			(layer "F.Fab")
		)
		(fp_line
			(start 0.120396 0.3048)
			(end 0.120396 0.2794)
			(stroke
				(width 0.1)
				(type default)
			)
			(layer "F.Fab")
		)
		(fp_line
			(start 0.120396 0.2794)
			(end -0.12065 0.2794)
			(stroke
				(width 0.1)
				(type default)
			)
			(layer "F.Fab")
		)
		(fp_line
			(start -0.12065 0.3048)
			(end -0.67945 0.3048)
			(stroke
				(width 0.1)
				(type default)
			)
			(layer "F.Fab")
		)
		(fp_line
			(start -0.12065 0.2794)
			(end -0.12065 0.3048)
			(stroke
				(width 0.1)
				(type default)
			)
			(layer "F.Fab")
		)
		(fp_line
			(start -0.12065 -0.2794)
			(end 0.12065 -0.2794)
			(stroke
				(width 0.1)
				(type default)
			)
			(layer "F.Fab")
		)
		(fp_line
			(start -0.12065 -0.305054)
			(end -0.12065 -0.2794)
			(stroke
				(width 0.1)
				(type default)
			)
			(layer "F.Fab")
		)
		(fp_line
			(start -0.67945 0.3048)
			(end -0.67945 -0.305054)
			(stroke
				(width 0.1)
				(type default)
			)
			(layer "F.Fab")
		)
		(fp_line
			(start -0.67945 -0.305054)
			(end -0.12065 -0.305054)
			(stroke
				(width 0.1)
				(type default)
			)
			(layer "F.Fab")
		)
		(pad "1" smd rect
			(at -0.40005 0)
			(size 0.4572 0.508)
			(layers "F.Cu" "F.Mask" "F.Paste")
			(net "FAN_3_TACH_IL_R")
		)
		(pad "2" smd rect
			(at 0.40005 0)
			(size 0.4572 0.508)
			(layers "F.Cu" "F.Mask" "F.Paste")
			(net "FAN_3_TACH_IL")
		)
	)
	(footprint ""
		(layer "F.Cu")
		(at 32.893 -288.925)
		(property "Reference" "R5301"
			(at 0 0 0)
			(layer "F.SilkS")
			(hide yes)
			(effects
				(font
					(size 1.27 1.27)
				)
			)
		)
		(property "Value" ""
			(at 0 0 0)
			(layer "F.Fab")
			(effects
				(font
					(size 1.27 1.27)
				)
			)
		)
		(duplicate_pad_numbers_are_jumpers no)
		(fp_line
			(start -1.2954 -0.5842)
			(end 1.2954 -0.5842)
			(stroke
				(width 0.1524)
				(type default)
			)
			(layer "F.SilkS")
		)
		(fp_line
			(start -1.2954 0.5842)
			(end -1.2954 -0.5842)
			(stroke
				(width 0.1524)
				(type default)
			)
			(layer "F.SilkS")
		)
		(fp_line
			(start 1.2954 -0.5842)
			(end 1.2954 0.5842)
			(stroke
				(width 0.1524)
				(type default)
			)
			(layer "F.SilkS")
		)
		(fp_line
			(start 1.2954 0.5842)
			(end -1.2954 0.5842)
			(stroke
				(width 0.1524)
				(type default)
			)
			(layer "F.SilkS")
		)
		(fp_line
			(start -1.1938 -0.406654)
			(end -0.8636 -0.406654)
			(stroke
				(width 0.1)
				(type default)
			)
			(layer "F.Fab")
		)
		(fp_line
			(start -1.1938 0.4064)
			(end -1.1938 -0.406654)
			(stroke
				(width 0.1)
				(type default)
			)
			(layer "F.Fab")
		)
		(fp_line
			(start -0.8636 -0.4572)
			(end 0.8636 -0.4572)
			(stroke
				(width 0.1)
				(type default)
			)
			(layer "F.Fab")
		)
		(fp_line
			(start -0.8636 -0.406654)
			(end -0.8636 -0.4572)
			(stroke
				(width 0.1)
				(type default)
			)
			(layer "F.Fab")
		)
		(fp_line
			(start -0.8636 0.4064)
			(end -1.1938 0.4064)
			(stroke
				(width 0.1)
				(type default)
			)
			(layer "F.Fab")
		)
		(fp_line
			(start -0.8636 0.4318)
			(end -0.8636 0.4064)
			(stroke
				(width 0.1)
				(type default)
			)
			(layer "F.Fab")
		)
		(fp_line
			(start -0.8636 0.4572)
			(end -0.8636 0.4318)
			(stroke
				(width 0.1)
				(type default)
			)
			(layer "F.Fab")
		)
		(fp_line
			(start 0.8636 -0.4572)
			(end 0.8636 -0.406654)
			(stroke
				(width 0.1)
				(type default)
			)
			(layer "F.Fab")
		)
		(fp_line
			(start 0.8636 -0.406654)
			(end 1.1938 -0.406654)
			(stroke
				(width 0.1)
				(type default)
			)
			(layer "F.Fab")
		)
		(fp_line
			(start 0.8636 0.4064)
			(end 0.8636 0.4572)
			(stroke
				(width 0.1)
				(type default)
			)
			(layer "F.Fab")
		)
		(fp_line
			(start 0.8636 0.4572)
			(end -0.8636 0.4572)
			(stroke
				(width 0.1)
				(type default)
			)
			(layer "F.Fab")
		)
		(fp_line
			(start 1.1938 -0.406654)
			(end 1.1938 0.4064)
			(stroke
				(width 0.1)
				(type default)
			)
			(layer "F.Fab")
		)
		(fp_line
			(start 1.1938 0.4064)
			(end 0.8636 0.4064)
			(stroke
				(width 0.1)
				(type default)
			)
			(layer "F.Fab")
		)
		(pad "1" smd rect
			(at -0.7366 0 270)
			(size 0.7112 0.8128)
			(layers "F.Cu" "F.Mask" "F.Paste")
			(net "P52V_FAN_0")
		)
		(pad "2" smd rect
			(at 0.7366 0 270)
			(size 0.7112 0.8128)
			(layers "F.Cu" "F.Mask" "F.Paste")
			(net "FAN_0_TACH_OL_R")
		)
	)
	(footprint ""
		(layer "F.Cu")
		(at 34.925 -293.116)
		(property "Reference" "R5525"
			(at 0 0 0)
			(layer "F.SilkS")
			(hide yes)
			(effects
				(font
					(size 1.27 1.27)
				)
			)
		)
		(property "Value" ""
			(at 0 0 0)
			(layer "F.Fab")
			(effects
				(font
					(size 1.27 1.27)
				)
			)
		)
		(duplicate_pad_numbers_are_jumpers no)
		(fp_line
			(start -0.7874 -0.4064)
			(end 0.7874 -0.4064)
			(stroke
				(width 0.1524)
				(type default)
			)
			(layer "F.SilkS")
		)
		(fp_line
			(start -0.7874 0.4064)
			(end -0.7874 -0.4064)
			(stroke
				(width 0.1524)
				(type default)
			)
			(layer "F.SilkS")
		)
		(fp_line
			(start 0.7874 -0.4064)
			(end 0.7874 0.4064)
			(stroke
				(width 0.1524)
				(type default)
			)
			(layer "F.SilkS")
		)
		(fp_line
			(start 0.7874 0.4064)
			(end -0.7874 0.4064)
			(stroke
				(width 0.1524)
				(type default)
			)
			(layer "F.SilkS")
		)
		(fp_line
			(start -0.67945 -0.305054)
			(end -0.12065 -0.305054)
			(stroke
				(width 0.1)
				(type default)
			)
			(layer "F.Fab")
		)
		(fp_line
			(start -0.67945 0.3048)
			(end -0.67945 -0.305054)
			(stroke
				(width 0.1)
				(type default)
			)
			(layer "F.Fab")
		)
		(fp_line
			(start -0.12065 -0.305054)
			(end -0.12065 -0.2794)
			(stroke
				(width 0.1)
				(type default)
			)
			(layer "F.Fab")
		)
		(fp_line
			(start -0.12065 -0.2794)
			(end 0.12065 -0.2794)
			(stroke
				(width 0.1)
				(type default)
			)
			(layer "F.Fab")
		)
		(fp_line
			(start -0.12065 0.2794)
			(end -0.12065 0.3048)
			(stroke
				(width 0.1)
				(type default)
			)
			(layer "F.Fab")
		)
		(fp_line
			(start -0.12065 0.3048)
			(end -0.67945 0.3048)
			(stroke
				(width 0.1)
				(type default)
			)
			(layer "F.Fab")
		)
		(fp_line
			(start 0.120396 0.2794)
			(end -0.12065 0.2794)
			(stroke
				(width 0.1)
				(type default)
			)
			(layer "F.Fab")
		)
		(fp_line
			(start 0.120396 0.3048)
			(end 0.120396 0.2794)
			(stroke
				(width 0.1)
				(type default)
			)
			(layer "F.Fab")
		)
		(fp_line
			(start 0.12065 -0.3048)
			(end 0.67945 -0.3048)
			(stroke
				(width 0.1)
				(type default)
			)
			(layer "F.Fab")
		)
		(fp_line
			(start 0.12065 -0.2794)
			(end 0.12065 -0.3048)
			(stroke
				(width 0.1)
				(type default)
			)
			(layer "F.Fab")
		)
		(fp_line
			(start 0.67945 -0.3048)
			(end 0.67945 0.3048)
			(stroke
				(width 0.1)
				(type default)
			)
			(layer "F.Fab")
		)
		(fp_line
			(start 0.67945 0.3048)
			(end 0.120396 0.3048)
			(stroke
				(width 0.1)
				(type default)
			)
			(layer "F.Fab")
		)
		(pad "1" smd rect
			(at -0.40005 0 180)
			(size 0.4572 0.508)
			(layers "F.Cu" "F.Mask" "F.Paste")
			(net "P12V_LED_FAN0")
		)
		(pad "2" smd rect
			(at 0.40005 0 180)
			(size 0.4572 0.508)
			(layers "F.Cu" "F.Mask" "F.Paste")
			(net "FAN_0_OK_LED_R_N")
		)
	)
	(footprint ""
		(layer "F.Cu")
		(at 2.794 -186.436)
		(property "Reference" "R315"
			(at 0 0 0)
			(layer "F.SilkS")
			(hide yes)
			(effects
				(font
					(size 1.27 1.27)
				)
			)
		)
		(property "Value" ""
			(at 0 0 0)
			(layer "F.Fab")
			(effects
				(font
					(size 1.27 1.27)
				)
			)
		)
		(duplicate_pad_numbers_are_jumpers no)
		(fp_line
			(start -0.7874 -0.4064)
			(end 0.7874 -0.4064)
			(stroke
				(width 0.1524)
				(type default)
			)
			(layer "F.SilkS")
		)
		(fp_line
			(start -0.7874 0.4064)
			(end -0.7874 -0.4064)
			(stroke
				(width 0.1524)
				(type default)
			)
			(layer "F.SilkS")
		)
		(fp_line
			(start 0.7874 -0.4064)
			(end 0.7874 0.4064)
			(stroke
				(width 0.1524)
				(type default)
			)
			(layer "F.SilkS")
		)
		(fp_line
			(start 0.7874 0.4064)
			(end -0.7874 0.4064)
			(stroke
				(width 0.1524)
				(type default)
			)
			(layer "F.SilkS")
		)
		(fp_line
			(start -0.67945 -0.305054)
			(end -0.12065 -0.305054)
			(stroke
				(width 0.1)
				(type default)
			)
			(layer "F.Fab")
		)
		(fp_line
			(start -0.67945 0.3048)
			(end -0.67945 -0.305054)
			(stroke
				(width 0.1)
				(type default)
			)
			(layer "F.Fab")
		)
		(fp_line
			(start -0.12065 -0.305054)
			(end -0.12065 -0.2794)
			(stroke
				(width 0.1)
				(type default)
			)
			(layer "F.Fab")
		)
		(fp_line
			(start -0.12065 -0.2794)
			(end 0.12065 -0.2794)
			(stroke
				(width 0.1)
				(type default)
			)
			(layer "F.Fab")
		)
		(fp_line
			(start -0.12065 0.2794)
			(end -0.12065 0.3048)
			(stroke
				(width 0.1)
				(type default)
			)
			(layer "F.Fab")
		)
		(fp_line
			(start -0.12065 0.3048)
			(end -0.67945 0.3048)
			(stroke
				(width 0.1)
				(type default)
			)
			(layer "F.Fab")
		)
		(fp_line
			(start 0.120396 0.2794)
			(end -0.12065 0.2794)
			(stroke
				(width 0.1)
				(type default)
			)
			(layer "F.Fab")
		)
		(fp_line
			(start 0.120396 0.3048)
			(end 0.120396 0.2794)
			(stroke
				(width 0.1)
				(type default)
			)
			(layer "F.Fab")
		)
		(fp_line
			(start 0.12065 -0.3048)
			(end 0.67945 -0.3048)
			(stroke
				(width 0.1)
				(type default)
			)
			(layer "F.Fab")
		)
		(fp_line
			(start 0.12065 -0.2794)
			(end 0.12065 -0.3048)
			(stroke
				(width 0.1)
				(type default)
			)
			(layer "F.Fab")
		)
		(fp_line
			(start 0.67945 -0.3048)
			(end 0.67945 0.3048)
			(stroke
				(width 0.1)
				(type default)
			)
			(layer "F.Fab")
		)
		(fp_line
			(start 0.67945 0.3048)
			(end 0.120396 0.3048)
			(stroke
				(width 0.1)
				(type default)
			)
			(layer "F.Fab")
		)
		(pad "1" smd circle
			(at -0.40005 0)
			(size 0 0)
			(layers "F.Cu" "F.Mask" "F.Paste")
			(net "GND")
		)
		(pad "2" smd circle
			(at 0.40005 0)
			(size 0 0)
			(layers "F.Cu" "F.Mask" "F.Paste")
			(net "FRU_ADDR2")
		)
	)
	(footprint ""
		(layer "F.Cu")
		(at 18.669 -104.14)
		(property "Reference" "C2034"
			(at 0 0 0)
			(layer "F.SilkS")
			(hide yes)
			(effects
				(font
					(size 1.27 1.27)
				)
			)
		)
		(property "Value" ""
			(at 0 0 0)
			(layer "F.Fab")
			(effects
				(font
					(size 1.27 1.27)
				)
			)
		)
		(duplicate_pad_numbers_are_jumpers no)
		(fp_line
			(start -0.7874 -0.4064)
			(end 0.7874 -0.4064)
			(stroke
				(width 0.1524)
				(type default)
			)
			(layer "F.SilkS")
		)
		(fp_line
			(start -0.7874 0.4064)
			(end -0.7874 -0.4064)
			(stroke
				(width 0.1524)
				(type default)
			)
			(layer "F.SilkS")
		)
		(fp_line
			(start 0.7874 -0.4064)
			(end 0.7874 0.4064)
			(stroke
				(width 0.1524)
				(type default)
			)
			(layer "F.SilkS")
		)
		(fp_line
			(start 0.7874 0.4064)
			(end -0.7874 0.4064)
			(stroke
				(width 0.1524)
				(type default)
			)
			(layer "F.SilkS")
		)
		(fp_line
			(start -0.67945 -0.305054)
			(end -0.12065 -0.305054)
			(stroke
				(width 0.1)
				(type default)
			)
			(layer "F.Fab")
		)
		(fp_line
			(start -0.67945 0.3048)
			(end -0.67945 -0.305054)
			(stroke
				(width 0.1)
				(type default)
			)
			(layer "F.Fab")
		)
		(fp_line
			(start -0.12065 -0.305054)
			(end -0.12065 -0.2794)
			(stroke
				(width 0.1)
				(type default)
			)
			(layer "F.Fab")
		)
		(fp_line
			(start -0.12065 -0.2794)
			(end 0.12065 -0.2794)
			(stroke
				(width 0.1)
				(type default)
			)
			(layer "F.Fab")
		)
		(fp_line
			(start -0.12065 0.2794)
			(end -0.12065 0.3048)
			(stroke
				(width 0.1)
				(type default)
			)
			(layer "F.Fab")
		)
		(fp_line
			(start -0.12065 0.3048)
			(end -0.67945 0.3048)
			(stroke
				(width 0.1)
				(type default)
			)
			(layer "F.Fab")
		)
		(fp_line
			(start 0.120396 0.2794)
			(end -0.12065 0.2794)
			(stroke
				(width 0.1)
				(type default)
			)
			(layer "F.Fab")
		)
		(fp_line
			(start 0.120396 0.3048)
			(end 0.120396 0.2794)
			(stroke
				(width 0.1)
				(type default)
			)
			(layer "F.Fab")
		)
		(fp_line
			(start 0.12065 -0.3048)
			(end 0.67945 -0.3048)
			(stroke
				(width 0.1)
				(type default)
			)
			(layer "F.Fab")
		)
		(fp_line
			(start 0.12065 -0.2794)
			(end 0.12065 -0.3048)
			(stroke
				(width 0.1)
				(type default)
			)
			(layer "F.Fab")
		)
		(fp_line
			(start 0.67945 -0.3048)
			(end 0.67945 0.3048)
			(stroke
				(width 0.1)
				(type default)
			)
			(layer "F.Fab")
		)
		(fp_line
			(start 0.67945 0.3048)
			(end 0.120396 0.3048)
			(stroke
				(width 0.1)
				(type default)
			)
			(layer "F.Fab")
		)
		(pad "1" smd circle
			(at -0.40005 0)
			(size 0 0)
			(layers "F.Cu" "F.Mask" "F.Paste")
			(net "FAN_5_TACH_IL_R")
		)
		(pad "2" smd circle
			(at 0.40005 0)
			(size 0 0)
			(layers "F.Cu" "F.Mask" "F.Paste")
			(net "GND")
		)
	)
	(footprint ""
		(layer "F.Cu")
		(at 14.351 -112.706912 180)
		(property "Reference" "D245"
			(at 4.191 0.042418 0)
			(unlocked yes)
			(layer "F.SilkS")
			(effects
				(font
					(size 0.7874 0.5842)
					(thickness 0.1524)
				)
				(justify left)
			)
		)
		(property "Value" ""
			(at 0 0 180)
			(layer "F.Fab")
			(effects
				(font
					(size 1.27 1.27)
				)
			)
		)
		(duplicate_pad_numbers_are_jumpers no)
		(fp_line
			(start 0.94488 0.450088)
			(end 0.94488 -0.450088)
			(stroke
				(width 0.1524)
				(type default)
			)
			(layer "F.SilkS")
		)
		(fp_line
			(start 0.94488 -0.450088)
			(end -0.854964 -0.450088)
			(stroke
				(width 0.1524)
				(type default)
			)
			(layer "F.SilkS")
		)
		(fp_line
			(start 0.870458 -0.2794)
			(end 0.845058 0.4064)
			(stroke
				(width 0.1524)
				(type default)
			)
			(layer "F.SilkS")
		)
		(fp_line
			(start 0.845058 0.4064)
			(end 0.845058 -0.381)
			(stroke
				(width 0.1524)
				(type default)
			)
			(layer "F.SilkS")
		)
		(fp_line
			(start -0.854964 0.450088)
			(end 0.925068 0.450088)
			(stroke
				(width 0.1524)
				(type default)
			)
			(layer "F.SilkS")
		)
		(fp_line
			(start -0.854964 -0.450088)
			(end -0.854964 0.450088)
			(stroke
				(width 0.1524)
				(type default)
			)
			(layer "F.SilkS")
		)
		(fp_line
			(start 0.54991 0.350012)
			(end 0.54991 -0.350012)
			(stroke
				(width 0.1)
				(type default)
			)
			(layer "F.Fab")
		)
		(fp_line
			(start 0.54991 -0.350012)
			(end -0.54991 -0.350012)
			(stroke
				(width 0.1)
				(type default)
			)
			(layer "F.Fab")
		)
		(fp_line
			(start -0.54991 0.350012)
			(end 0.54991 0.350012)
			(stroke
				(width 0.1)
				(type default)
			)
			(layer "F.Fab")
		)
		(fp_line
			(start -0.54991 -0.350012)
			(end -0.54991 0.350012)
			(stroke
				(width 0.1)
				(type default)
			)
			(layer "F.Fab")
		)
		(fp_text user "-"
			(at 1.778 -0.470662 0)
			(unlocked yes)
			(layer "F.SilkS")
			(effects
				(font
					(size 1.905 1.4224)
					(thickness 0.1524)
				)
				(justify left)
			)
		)
		(fp_text user "+"
			(at -0.635 -0.470662 0)
			(unlocked yes)
			(layer "F.SilkS")
			(effects
				(font
					(size 1.905 1.4224)
					(thickness 0.1524)
				)
				(justify left)
			)
		)
		(fp_text user "-"
			(at 2.48539 0.239014 0)
			(unlocked yes)
			(layer "F.Fab")
			(effects
				(font
					(size 1.905 1.4224)
					(thickness 0.1524)
				)
				(justify left)
			)
		)
		(fp_text user "+"
			(at -0.808228 0.239014 0)
			(unlocked yes)
			(layer "F.Fab")
			(effects
				(font
					(size 1.905 1.4224)
					(thickness 0.1524)
				)
				(justify left)
			)
		)
		(pad "A" smd rect
			(at -0.424942 0 180)
			(size 0.5588 0.6096)
			(layers "F.Cu" "F.Mask" "F.Paste")
			(net "GND")
		)
		(pad "C" smd rect
			(at 0.424942 0)
			(size 0.5588 0.6096)
			(layers "F.Cu" "F.Mask" "F.Paste")
			(net "FAN_5_FAIL_R_LED_N")
		)
	)
)
